(kicad_pcb
	(version 20241229)
	(generator "pcbnew")
	(generator_version "9.0")
	(general
		(thickness 1.62)
		(legacy_teardrops no)
	)
	(paper "A3")
	(title_block
		(title "COM Express 7 Baseboard")
		(date "2025-02-04")
		(rev "1.1.2")
		(company "Antmicro Ltd")
		(comment 1 "www.antmicro.com")
		(comment 9 "footprints 59-63 of 802")
	)
	(layers
		(0 "F.Cu" signal)
		(4 "In1.Cu" signal)
		(6 "In2.Cu" signal)
		(8 "In3.Cu" signal)
		(10 "In4.Cu" signal)
		(12 "In5.Cu" signal)
		(14 "In6.Cu" signal)
		(2 "B.Cu" signal)
		(9 "F.Adhes" user "F.Adhesive")
		(11 "B.Adhes" user "B.Adhesive")
		(13 "F.Paste" user)
		(15 "B.Paste" user)
		(5 "F.SilkS" user "F.Silkscreen")
		(7 "B.SilkS" user "B.Silkscreen")
		(1 "F.Mask" user)
		(3 "B.Mask" user)
		(17 "Dwgs.User" user "User.Drawings")
		(19 "Cmts.User" user "User.Comments")
		(21 "Eco1.User" user "User.Eco1")
		(23 "Eco2.User" user "User.Eco2")
		(25 "Edge.Cuts" user)
		(27 "Margin" user)
		(31 "F.CrtYd" user "F.Courtyard")
		(29 "B.CrtYd" user "B.Courtyard")
		(35 "F.Fab" user)
		(33 "B.Fab" user)
	)
	(footprint "antmicro-footprints:R_0402_1005Metric"
		(layer "F.Cu")
		(at 306.14 131.04 180)
		(descr "Resistor SMD 0402")
		(tags "resistor SMD 0402")
		(property "Reference" "R102"
			(at -1.66 -1.37 0)
			(layer "F.SilkS")
			(effects
				(font
					(size 0.7 0.7)
					(thickness 0.15)
				)
				(justify right bottom)
			)
		)
		(property "Value" "R_0R_0402"
			(at -1.011843 1.772047 0)
			(layer "F.Fab")
			(effects
				(font
					(size 0.7 0.7)
					(thickness 0.15)
				)
				(justify right bottom)
			)
		)
		(property "Datasheet" "https://industrial.panasonic.com/cdbs/www-data/pdf/RDA0000/AOA0000C301.pdf"
			(at 0 0 180)
			(layer "F.Fab")
			(hide yes)
			(effects
				(font
					(size 1.27 1.27)
					(thickness 0.15)
				)
			)
		)
		(property "Author" "Antmicro"
			(at 612.28 262.08 0)
			(layer "F.Fab")
			(hide yes)
			(effects
				(font
					(size 1 1)
					(thickness 0.15)
				)
			)
		)
		(property "Current" "1A"
			(at 612.28 262.08 0)
			(layer "F.Fab")
			(hide yes)
			(effects
				(font
					(size 1 1)
					(thickness 0.15)
				)
			)
		)
		(property "License" "Apache-2.0"
			(at 612.28 262.08 0)
			(layer "F.Fab")
			(hide yes)
			(effects
				(font
					(size 1 1)
					(thickness 0.15)
				)
			)
		)
		(property "MPN" "ERJ2GE0R00X"
			(at 612.28 262.08 0)
			(layer "F.Fab")
			(hide yes)
			(effects
				(font
					(size 1 1)
					(thickness 0.15)
				)
			)
		)
		(property "Manufacturer" "Panasonic"
			(at 612.28 262.08 0)
			(layer "F.Fab")
			(hide yes)
			(effects
				(font
					(size 1 1)
					(thickness 0.15)
				)
			)
		)
		(property "Public" "False"
			(at 612.28 262.08 0)
			(layer "F.Fab")
			(hide yes)
			(effects
				(font
					(size 1 1)
					(thickness 0.15)
				)
			)
		)
		(property "Tolerance" ""
			(at 612.28 262.08 0)
			(layer "F.Fab")
			(hide yes)
			(effects
				(font
					(size 1 1)
					(thickness 0.15)
				)
			)
		)
		(property "Val" "0R"
			(at 612.28 262.08 0)
			(layer "F.Fab")
			(hide yes)
			(effects
				(font
					(size 1 1)
					(thickness 0.15)
				)
			)
		)
		(sheetname "Power")
		(sheetfile "power.kicad_sch")
		(attr smd)
		(fp_rect
			(start -0.925 -0.47)
			(end 0.925 0.47)
			(stroke
				(width 0.05)
				(type default)
			)
			(fill no)
			(layer "F.CrtYd")
		)
		(fp_rect
			(start -0.5 -0.25)
			(end 0.5 0.25)
			(stroke
				(width 0.15)
				(type solid)
			)
			(fill no)
			(layer "F.Fab")
		)
		(pad "1" smd roundrect
			(at -0.48 0 180)
			(size 0.59 0.64)
			(layers "F.Cu" "F.Mask" "F.Paste")
			(roundrect_rratio 0.25)
			(net 578 "/Power/PG_{1V0}")
			(pintype "passive")
			(teardrops
				(best_length_ratio 0.2)
				(max_length 1)
				(best_width_ratio 0.9)
				(max_width 2)
				(curved_edges yes)
				(filter_ratio 0.9)
				(enabled yes)
				(allow_two_segments yes)
				(prefer_zone_connections yes)
			)
		)
		(pad "2" smd roundrect
			(at 0.48 0 180)
			(size 0.59 0.64)
			(layers "F.Cu" "F.Mask" "F.Paste")
			(roundrect_rratio 0.25)
			(net 582 "Net-(U20-~{MR})")
			(pintype "passive")
			(teardrops
				(best_length_ratio 0.2)
				(max_length 1)
				(best_width_ratio 0.9)
				(max_width 2)
				(curved_edges yes)
				(filter_ratio 0.9)
				(enabled yes)
				(allow_two_segments yes)
				(prefer_zone_connections yes)
			)
		)
	)
	(footprint "antmicro-footprints:R_0402_1005Metric"
		(layer "F.Cu")
		(at 211.28 130.425 180)
		(descr "Resistor SMD 0402")
		(tags "resistor SMD 0402")
		(property "Reference" "R195"
			(at 0.83 -0.735 0)
			(layer "F.SilkS")
			(effects
				(font
					(size 0.7 0.7)
					(thickness 0.15)
				)
				(justify right bottom)
			)
		)
		(property "Value" "R_0R_0402"
			(at -1.011843 1.772047 0)
			(layer "F.Fab")
			(effects
				(font
					(size 0.7 0.7)
					(thickness 0.15)
				)
				(justify right bottom)
			)
		)
		(property "Datasheet" "https://industrial.panasonic.com/cdbs/www-data/pdf/RDA0000/AOA0000C301.pdf"
			(at 0 0 180)
			(layer "F.Fab")
			(hide yes)
			(effects
				(font
					(size 1.27 1.27)
					(thickness 0.15)
				)
			)
		)
		(property "Author" "Antmicro"
			(at 422.56 260.85 0)
			(layer "F.Fab")
			(hide yes)
			(effects
				(font
					(size 1 1)
					(thickness 0.15)
				)
			)
		)
		(property "Current" "1A"
			(at 422.56 260.85 0)
			(layer "F.Fab")
			(hide yes)
			(effects
				(font
					(size 1 1)
					(thickness 0.15)
				)
			)
		)
		(property "License" "Apache-2.0"
			(at 422.56 260.85 0)
			(layer "F.Fab")
			(hide yes)
			(effects
				(font
					(size 1 1)
					(thickness 0.15)
				)
			)
		)
		(property "MPN" "ERJ2GE0R00X"
			(at 422.56 260.85 0)
			(layer "F.Fab")
			(hide yes)
			(effects
				(font
					(size 1 1)
					(thickness 0.15)
				)
			)
		)
		(property "Manufacturer" "Panasonic"
			(at 422.56 260.85 0)
			(layer "F.Fab")
			(hide yes)
			(effects
				(font
					(size 1 1)
					(thickness 0.15)
				)
			)
		)
		(property "Public" "False"
			(at 422.56 260.85 0)
			(layer "F.Fab")
			(hide yes)
			(effects
				(font
					(size 1 1)
					(thickness 0.15)
				)
			)
		)
		(property "Tolerance" ""
			(at 422.56 260.85 0)
			(layer "F.Fab")
			(hide yes)
			(effects
				(font
					(size 1 1)
					(thickness 0.15)
				)
			)
		)
		(property "Val" "0R"
			(at 422.56 260.85 0)
			(layer "F.Fab")
			(hide yes)
			(effects
				(font
					(size 1 1)
					(thickness 0.15)
				)
			)
		)
		(sheetname "PCIe misc")
		(sheetfile "pcie_misc.kicad_sch")
		(attr smd)
		(fp_rect
			(start -0.925 -0.47)
			(end 0.925 0.47)
			(stroke
				(width 0.05)
				(type default)
			)
			(fill no)
			(layer "F.CrtYd")
		)
		(fp_rect
			(start -0.5 -0.25)
			(end 0.5 0.25)
			(stroke
				(width 0.15)
				(type solid)
			)
			(fill no)
			(layer "F.Fab")
		)
		(pad "1" smd roundrect
			(at -0.48 0 180)
			(size 0.59 0.64)
			(layers "F.Cu" "F.Mask" "F.Paste")
			(roundrect_rratio 0.25)
			(net 614 "/PCIe misc/DIF1-")
			(pintype "passive")
			(teardrops
				(best_length_ratio 0.2)
				(max_length 1)
				(best_width_ratio 0.9)
				(max_width 2)
				(curved_edges yes)
				(filter_ratio 0.9)
				(enabled yes)
				(allow_two_segments yes)
				(prefer_zone_connections yes)
			)
		)
		(pad "2" smd roundrect
			(at 0.48 0 180)
			(size 0.59 0.64)
			(layers "F.Cu" "F.Mask" "F.Paste")
			(roundrect_rratio 0.25)
			(net 192 "/OCuLink/PCIe_{REF0}.CK+")
			(pintype "passive")
			(teardrops
				(best_length_ratio 0.2)
				(max_length 1)
				(best_width_ratio 0.9)
				(max_width 2)
				(curved_edges yes)
				(filter_ratio 0.9)
				(enabled yes)
				(allow_two_segments yes)
				(prefer_zone_connections yes)
			)
		)
	)
	(footprint "antmicro-footprints:VSSOP-8_2.3x2mm_P0.5mm"
		(layer "F.Cu")
		(at 249.725 131.51 -90)
		(property "Reference" "U33"
			(at 2.75 -1.125 180)
			(layer "F.SilkS")
			(effects
				(font
					(size 0.7 0.7)
					(thickness 0.15)
				)
				(justify right bottom)
			)
		)
		(property "Value" "74AUP2G132"
			(at 0 2.258 90)
			(layer "F.Fab")
			(effects
				(font
					(size 0.7 0.7)
					(thickness 0.15)
				)
				(justify right bottom)
			)
		)
		(property "Datasheet" "https://assets.nexperia.com/documents/data-sheet/74AUP2G132.pdf"
			(at 0 0 270)
			(layer "F.Fab")
			(hide yes)
			(effects
				(font
					(size 1.27 1.27)
					(thickness 0.15)
				)
			)
		)
		(property "Author" "Antmicro"
			(at 118.215 381.235 0)
			(layer "F.Fab")
			(hide yes)
			(effects
				(font
					(size 1 1)
					(thickness 0.15)
				)
			)
		)
		(property "License" "Apache-2.0"
			(at 118.215 381.235 0)
			(layer "F.Fab")
			(hide yes)
			(effects
				(font
					(size 1 1)
					(thickness 0.15)
				)
			)
		)
		(property "MPN" "74AUP2G132"
			(at 118.215 381.235 0)
			(layer "F.Fab")
			(hide yes)
			(effects
				(font
					(size 1 1)
					(thickness 0.15)
				)
			)
		)
		(property "Manufacturer" "Nexperia"
			(at 118.215 381.235 0)
			(layer "F.Fab")
			(hide yes)
			(effects
				(font
					(size 1 1)
					(thickness 0.15)
				)
			)
		)
		(sheetname "Com Express 7 MGMT")
		(sheetfile "com_express_7_mgmt.kicad_sch")
		(attr smd)
		(fp_line
			(start 0.825 1.007)
			(end -0.82 1.007)
			(stroke
				(width 0.15)
				(type solid)
			)
			(layer "F.SilkS")
		)
		(fp_line
			(start -0.82 -0.992)
			(end 0.825 -0.992)
			(stroke
				(width 0.15)
				(type solid)
			)
			(layer "F.SilkS")
		)
		(fp_circle
			(center -1.402 -1.192)
			(end -1.352 -1.192)
			(stroke
				(width 0.15)
				(type solid)
			)
			(fill yes)
			(layer "F.SilkS")
		)
		(fp_rect
			(start 1.8 1.35)
			(end -1.8 -1.35)
			(stroke
				(width 0.05)
				(type solid)
			)
			(fill no)
			(layer "F.CrtYd")
		)
		(fp_line
			(start -0.7 -0.99)
			(end -1.14 -0.55)
			(stroke
				(width 0.15)
				(type solid)
			)
			(layer "F.Fab")
		)
		(fp_rect
			(start -1.147 -0.992)
			(end 1.151 1.007)
			(stroke
				(width 0.15)
				(type solid)
			)
			(fill no)
			(layer "F.Fab")
		)
		(pad "1" smd rect
			(at -1.372 -0.742 270)
			(size 0.75 0.4)
			(layers "F.Cu" "F.Mask" "F.Paste")
			(net 138 "Net-(U33-1A)")
			(pinfunction "1A")
			(pintype "input")
			(teardrops
				(best_length_ratio 0.2)
				(max_length 1)
				(best_width_ratio 0.9)
				(max_width 2)
				(curved_edges yes)
				(filter_ratio 0.9)
				(enabled yes)
				(allow_two_segments yes)
				(prefer_zone_connections yes)
			)
		)
		(pad "2" smd rect
			(at -1.372 -0.244 270)
			(size 0.75 0.3)
			(layers "F.Cu" "F.Mask" "F.Paste")
			(net 138 "Net-(U33-1A)")
			(pinfunction "1B")
			(pintype "input")
			(teardrops
				(best_length_ratio 0.2)
				(max_length 1)
				(best_width_ratio 0.9)
				(max_width 2)
				(curved_edges yes)
				(filter_ratio 0.9)
				(enabled yes)
				(allow_two_segments yes)
				(prefer_zone_connections yes)
			)
		)
		(pad "3" smd rect
			(at -1.372 0.256 270)
			(size 0.75 0.3)
			(layers "F.Cu" "F.Mask" "F.Paste")
			(net 546 "/Com Express 7 MGMT/~{COM7}")
			(pinfunction "2Y")
			(pintype "output")
			(teardrops
				(best_length_ratio 0.2)
				(max_length 1)
				(best_width_ratio 0.9)
				(max_width 2)
				(curved_edges yes)
				(filter_ratio 0.9)
				(enabled yes)
				(allow_two_segments yes)
				(prefer_zone_connections yes)
			)
		)
		(pad "4" smd rect
			(at -1.372 0.757 270)
			(size 0.75 0.4)
			(layers "F.Cu" "F.Mask" "F.Paste")
			(net 1 "GND")
			(pinfunction "GND")
			(pintype "power_in")
			(teardrops
				(best_length_ratio 0.2)
				(max_length 1)
				(best_width_ratio 0.9)
				(max_width 2)
				(curved_edges yes)
				(filter_ratio 0.9)
				(enabled yes)
				(allow_two_segments yes)
				(prefer_zone_connections yes)
			)
		)
		(pad "5" smd rect
			(at 1.377 0.757 270)
			(size 0.75 0.4)
			(layers "F.Cu" "F.Mask" "F.Paste")
			(net 785 "Net-(U33-1Y)")
			(pinfunction "2A")
			(pintype "input")
			(teardrops
				(best_length_ratio 0.2)
				(max_length 1)
				(best_width_ratio 0.9)
				(max_width 2)
				(curved_edges yes)
				(filter_ratio 0.9)
				(enabled yes)
				(allow_two_segments yes)
				(prefer_zone_connections yes)
			)
		)
		(pad "6" smd rect
			(at 1.377 0.256 270)
			(size 0.75 0.3)
			(layers "F.Cu" "F.Mask" "F.Paste")
			(net 434 "/Com Express 7 MGMT/~{TYPE1}")
			(pinfunction "2B")
			(pintype "input")
			(teardrops
				(best_length_ratio 0.2)
				(max_length 1)
				(best_width_ratio 0.9)
				(max_width 2)
				(curved_edges yes)
				(filter_ratio 0.9)
				(enabled yes)
				(allow_two_segments yes)
				(prefer_zone_connections yes)
			)
		)
		(pad "7" smd rect
			(at 1.377 -0.244 270)
			(size 0.75 0.3)
			(layers "F.Cu" "F.Mask" "F.Paste")
			(net 785 "Net-(U33-1Y)")
			(pinfunction "1Y")
			(pintype "output")
			(teardrops
				(best_length_ratio 0.2)
				(max_length 1)
				(best_width_ratio 0.9)
				(max_width 2)
				(curved_edges yes)
				(filter_ratio 0.9)
				(enabled yes)
				(allow_two_segments yes)
				(prefer_zone_connections yes)
			)
		)
		(pad "8" smd rect
			(at 1.377 -0.742 270)
			(size 0.75 0.4)
			(layers "F.Cu" "F.Mask" "F.Paste")
			(net 73 "+3V3_AON")
			(pinfunction "VCC")
			(pintype "power_in")
			(teardrops
				(best_length_ratio 0.2)
				(max_length 1)
				(best_width_ratio 0.9)
				(max_width 2)
				(curved_edges yes)
				(filter_ratio 0.9)
				(enabled yes)
				(allow_two_segments yes)
				(prefer_zone_connections yes)
			)
		)
	)
	(footprint "antmicro-footprints:R_0402_1005Metric"
		(layer "F.Cu")
		(at 314.765499 97.4365 -90)
		(descr "Resistor SMD 0402")
		(tags "resistor SMD 0402")
		(property "Reference" "R110"
			(at -10.1265 -4.734501 90)
			(layer "F.SilkS")
			(effects
				(font
					(size 0.7 0.7)
					(thickness 0.15)
				)
				(justify right bottom)
			)
		)
		(property "Value" "R_15k_0402"
			(at -1.011843 1.772047 90)
			(layer "F.Fab")
			(effects
				(font
					(size 0.7 0.7)
					(thickness 0.15)
				)
				(justify right bottom)
			)
		)
		(property "Datasheet" "https://www.bourns.com/docs/product-datasheets/cr.pdf"
			(at 0 0 270)
			(layer "F.Fab")
			(hide yes)
			(effects
				(font
					(size 1.27 1.27)
					(thickness 0.15)
				)
			)
		)
		(property "Author" "Antmicro"
			(at 217.328999 412.201999 0)
			(layer "F.Fab")
			(hide yes)
			(effects
				(font
					(size 1 1)
					(thickness 0.15)
				)
			)
		)
		(property "License" "Apache-2.0"
			(at 217.328999 412.201999 0)
			(layer "F.Fab")
			(hide yes)
			(effects
				(font
					(size 1 1)
					(thickness 0.15)
				)
			)
		)
		(property "MPN" "CR0402-FX-1502GLF"
			(at 217.328999 412.201999 0)
			(layer "F.Fab")
			(hide yes)
			(effects
				(font
					(size 1 1)
					(thickness 0.15)
				)
			)
		)
		(property "Manufacturer" "Bourns"
			(at 217.328999 412.201999 0)
			(layer "F.Fab")
			(hide yes)
			(effects
				(font
					(size 1 1)
					(thickness 0.15)
				)
			)
		)
		(property "Public" "False"
			(at 217.328999 412.201999 0)
			(layer "F.Fab")
			(hide yes)
			(effects
				(font
					(size 1 1)
					(thickness 0.15)
				)
			)
		)
		(property "Tolerance" "1%"
			(at 217.328999 412.201999 0)
			(layer "F.Fab")
			(hide yes)
			(effects
				(font
					(size 1 1)
					(thickness 0.15)
				)
			)
		)
		(property "Val" "15k"
			(at 217.328999 412.201999 0)
			(layer "F.Fab")
			(hide yes)
			(effects
				(font
					(size 1 1)
					(thickness 0.15)
				)
			)
		)
		(sheetname "Power")
		(sheetfile "power.kicad_sch")
		(attr smd)
		(fp_rect
			(start -0.925 -0.47)
			(end 0.925 0.47)
			(stroke
				(width 0.05)
				(type default)
			)
			(fill no)
			(layer "F.CrtYd")
		)
		(fp_rect
			(start -0.5 -0.25)
			(end 0.5 0.25)
			(stroke
				(width 0.15)
				(type solid)
			)
			(fill no)
			(layer "F.Fab")
		)
		(pad "1" smd roundrect
			(at -0.48 0 270)
			(size 0.59 0.64)
			(layers "F.Cu" "F.Mask" "F.Paste")
			(roundrect_rratio 0.25)
			(net 1 "GND")
			(pintype "passive")
			(teardrops
				(best_length_ratio 0.2)
				(max_length 1)
				(best_width_ratio 0.9)
				(max_width 2)
				(curved_edges yes)
				(filter_ratio 0.9)
				(enabled yes)
				(allow_two_segments yes)
				(prefer_zone_connections yes)
			)
		)
		(pad "2" smd roundrect
			(at 0.48 0 270)
			(size 0.59 0.64)
			(layers "F.Cu" "F.Mask" "F.Paste")
			(roundrect_rratio 0.25)
			(net 585 "Net-(U21-FB)")
			(pintype "passive")
			(teardrops
				(best_length_ratio 0.2)
				(max_length 1)
				(best_width_ratio 0.9)
				(max_width 2)
				(curved_edges yes)
				(filter_ratio 0.9)
				(enabled yes)
				(allow_two_segments yes)
				(prefer_zone_connections yes)
			)
		)
	)
	(footprint "antmicro-footprints:SOD-523"
		(layer "F.Cu")
		(at 113.2 86.41 -90)
		(property "Reference" "D1"
			(at -2.45 -0.45 90)
			(layer "F.SilkS")
			(effects
				(font
					(size 0.7 0.7)
					(thickness 0.15)
				)
				(justify right bottom)
			)
		)
		(property "Value" "PESD5Z5_0F"
			(at 0 1.499 90)
			(layer "F.Fab")
			(effects
				(font
					(size 0.7 0.7)
					(thickness 0.15)
				)
				(justify right bottom)
			)
		)
		(property "Datasheet" "https://assets.nexperia.com/documents/data-sheet/PESD5Z5_0.pdf"
			(at 0 0 270)
			(layer "F.Fab")
			(hide yes)
			(effects
				(font
					(size 1.27 1.27)
					(thickness 0.15)
				)
			)
		)
		(property "Author" "Antmicro"
			(at 26.79 199.61 0)
			(layer "F.Fab")
			(hide yes)
			(effects
				(font
					(size 1 1)
					(thickness 0.15)
				)
			)
		)
		(property "License" "Apache-2.0"
			(at 26.79 199.61 0)
			(layer "F.Fab")
			(hide yes)
			(effects
				(font
					(size 1 1)
					(thickness 0.15)
				)
			)
		)
		(property "MPN" "PESD5Z5.0F"
			(at 26.79 199.61 0)
			(layer "F.Fab")
			(hide yes)
			(effects
				(font
					(size 1 1)
					(thickness 0.15)
				)
			)
		)
		(property "Manufacturer" "Nexperia"
			(at 26.79 199.61 0)
			(layer "F.Fab")
			(hide yes)
			(effects
				(font
					(size 1 1)
					(thickness 0.15)
				)
			)
		)
		(property "Public" "False"
			(at 26.79 199.61 0)
			(layer "F.Fab")
			(hide yes)
			(effects
				(font
					(size 1 1)
					(thickness 0.15)
				)
			)
		)
		(sheetname "2xUSB3.0+RJ45")
		(sheetfile "usb3+rj45.kicad_sch")
		(attr smd)
		(fp_line
			(start -0.35 -0.5)
			(end -0.35 0.5)
			(stroke
				(width 0.15)
				(type solid)
			)
			(layer "F.SilkS")
		)
		(fp_rect
			(start -1 -0.6)
			(end 1 0.6)
			(stroke
				(width 0.05)
				(type solid)
			)
			(fill no)
			(layer "F.CrtYd")
		)
		(fp_line
			(start -0.652 0.423)
			(end 0.65 0.423)
			(stroke
				(width 0.15)
				(type solid)
			)
			(layer "F.Fab")
		)
		(fp_line
			(start -0.652 0.423)
			(end -0.652 -0.425)
			(stroke
				(width 0.15)
				(type solid)
			)
			(layer "F.Fab")
		)
		(fp_line
			(start -0.35 -0.4)
			(end -0.35 0.4)
			(stroke
				(width 0.15)
				(type solid)
			)
			(layer "F.Fab")
		)
		(fp_line
			(start -0.652 -0.425)
			(end 0.65 -0.425)
			(stroke
				(width 0.15)
				(type solid)
			)
			(layer "F.Fab")
		)
		(fp_line
			(start 0.65 -0.425)
			(end 0.65 0.423)
			(stroke
				(width 0.15)
				(type solid)
			)
			(layer "F.Fab")
		)
		(pad "1" smd roundrect
			(at -0.701 0 270)
			(size 0.5 0.6)
			(layers "F.Cu" "F.Mask" "F.Paste")
			(roundrect_rratio 0.25)
			(net 42 "/2xUSB3.0+RJ45/P1_VBUS")
			(pinfunction "C")
			(pintype "passive")
			(teardrops
				(best_length_ratio 0.2)
				(max_length 1)
				(best_width_ratio 0.9)
				(max_width 2)
				(curved_edges yes)
				(filter_ratio 0.9)
				(enabled yes)
				(allow_two_segments yes)
				(prefer_zone_connections yes)
			)
		)
		(pad "2" smd roundrect
			(at 0.699 0 270)
			(size 0.5 0.6)
			(layers "F.Cu" "F.Mask" "F.Paste")
			(roundrect_rratio 0.25)
			(net 1 "GND")
			(pinfunction "A")
			(pintype "passive")
			(teardrops
				(best_length_ratio 0.2)
				(max_length 1)
				(best_width_ratio 0.9)
				(max_width 2)
				(curved_edges yes)
				(filter_ratio 0.9)
				(enabled yes)
				(allow_two_segments yes)
				(prefer_zone_connections yes)
			)
		)
	)
)
